(kicad_pcb
	(version 20241229)
	(generator "pcbnew")
	(generator_version "9.0")
	(general
		(thickness 1.61)
		(legacy_teardrops no)
	)
	(paper "A3")
	(title_block
		(title "SO-DIMM DDR5 Tester")
		(date "2025-11-26")
		(rev "1.3.0")
		(comment 9 "footprints 626-627 of 627")
	)
	(layers
		(0 "F.Cu" signal)
		(4 "In1.Cu" power)
		(6 "In2.Cu" mixed)
		(8 "In3.Cu" power)
		(10 "In4.Cu" mixed)
		(12 "In5.Cu" power)
		(14 "In6.Cu" mixed)
		(16 "In7.Cu" power)
		(18 "In8.Cu" power)
		(20 "In9.Cu" mixed)
		(22 "In10.Cu" power)
		(2 "B.Cu" signal)
		(9 "F.Adhes" user "F.Adhesive")
		(11 "B.Adhes" user "B.Adhesive")
		(13 "F.Paste" user)
		(15 "B.Paste" user)
		(5 "F.SilkS" user "F.Silkscreen")
		(7 "B.SilkS" user "B.Silkscreen")
		(1 "F.Mask" user)
		(3 "B.Mask" user)
		(17 "Dwgs.User" user "User.Drawings")
		(19 "Cmts.User" user "User.Comments")
		(21 "Eco1.User" user "User.Eco1")
		(23 "Eco2.User" user "User.Eco2")
		(25 "Edge.Cuts" user)
		(27 "Margin" user)
		(31 "F.CrtYd" user "F.Courtyard")
		(29 "B.CrtYd" user "B.Courtyard")
		(35 "F.Fab" user)
		(33 "B.Fab" user)
	)
	(footprint "antmicro-footprints:C_0402_1005Metric"
		(layer "B.Cu")
		(at 142.875501 162.301)
		(descr "Capacitor SMD 0402 (1005 Metric), square (rectangular) end terminal, IPC_7351 nominal, (Body size source: IPC-SM-782 page 76, https://www.pcb-3d.com/wordpress/wp-content/uploads/ipc-sm-782a_amendment_1_and_2.pdf)")
		(tags "capacitor 0402")
		(property "Reference" "C63"
			(at 0 1.17 180)
			(layer "B.SilkS")
			(hide yes)
			(effects
				(font
					(size 0.7 0.7)
					(thickness 0.15)
				)
				(justify left bottom mirror)
			)
		)
		(property "Value" "C_100n_0402"
			(at 0 -1.169 180)
			(layer "B.Fab")
			(effects
				(font
					(size 0.7 0.7)
					(thickness 0.15)
				)
				(justify left bottom mirror)
			)
		)
		(property "Datasheet" "https://www.murata.com/products/productdetail?partno=GRM155R61H104KE14%23"
			(at 0 0 0)
			(layer "F.Fab")
			(hide yes)
			(effects
				(font
					(size 1.27 1.27)
					(thickness 0.15)
				)
			)
		)
		(property "Author" "Antmicro"
			(at 0 0 0)
			(layer "B.Fab")
			(hide yes)
			(effects
				(font
					(size 1 1)
					(thickness 0.15)
				)
				(justify mirror)
			)
		)
		(property "Dielectric" "X5R"
			(at 0 0 0)
			(layer "B.Fab")
			(hide yes)
			(effects
				(font
					(size 1 1)
					(thickness 0.15)
				)
				(justify mirror)
			)
		)
		(property "License" "Apache-2.0"
			(at 0 0 0)
			(layer "B.Fab")
			(hide yes)
			(effects
				(font
					(size 1 1)
					(thickness 0.15)
				)
				(justify mirror)
			)
		)
		(property "MPN" "GRM155R61H104KE14D"
			(at 0 0 0)
			(layer "B.Fab")
			(hide yes)
			(effects
				(font
					(size 1 1)
					(thickness 0.15)
				)
				(justify mirror)
			)
		)
		(property "Manufacturer" "Murata"
			(at 0 0 0)
			(layer "B.Fab")
			(hide yes)
			(effects
				(font
					(size 1 1)
					(thickness 0.15)
				)
				(justify mirror)
			)
		)
		(property "Val" "100n"
			(at 0 0 0)
			(layer "B.Fab")
			(hide yes)
			(effects
				(font
					(size 1 1)
					(thickness 0.15)
				)
				(justify mirror)
			)
		)
		(property "Voltage" "50V"
			(at 0 0 0)
			(layer "B.Fab")
			(hide yes)
			(effects
				(font
					(size 1 1)
					(thickness 0.15)
				)
				(justify mirror)
			)
		)
		(sheetname "/FPGA power/")
		(sheetfile "fpga-power.kicad_sch")
		(attr smd)
		(fp_rect
			(start -0.9656 0.4572)
			(end 0.9652 -0.4828)
			(stroke
				(width 0.05)
				(type solid)
			)
			(fill no)
			(layer "B.CrtYd")
		)
		(fp_line
			(start -0.5 -0.248)
			(end -0.5 0.25)
			(stroke
				(width 0.15)
				(type solid)
			)
			(layer "B.Fab")
		)
		(fp_line
			(start -0.5 0.25)
			(end 0.498 0.25)
			(stroke
				(width 0.15)
				(type solid)
			)
			(layer "B.Fab")
		)
		(fp_line
			(start 0.498 -0.248)
			(end -0.5 -0.248)
			(stroke
				(width 0.15)
				(type solid)
			)
			(layer "B.Fab")
		)
		(fp_line
			(start 0.498 0.25)
			(end 0.498 -0.248)
			(stroke
				(width 0.15)
				(type solid)
			)
			(layer "B.Fab")
		)
		(pad "1" smd roundrect
			(at -0.5 0 270)
			(size 0.6 0.6)
			(layers "B.Cu" "B.Mask" "B.Paste")
			(roundrect_rratio 0.25)
			(net 1 "GND")
			(pintype "passive")
		)
		(pad "2" smd roundrect
			(at 0.498 0)
			(size 0.6 0.6)
			(layers "B.Cu" "B.Mask" "B.Paste")
			(roundrect_rratio 0.25)
			(net 206 "+1V1")
			(pintype "passive")
		)
	)
	(footprint "antmicro-footprints:C_0603_1608Metric"
		(layer "B.Cu")
		(at 153.275001 166.7025)
		(descr "Capacitor SMD 0603")
		(tags "capacitor 0603")
		(property "Reference" "C60"
			(at 0 0.9 0)
			(layer "B.SilkS")
			(hide yes)
			(effects
				(font
					(size 0.7 0.7)
					(thickness 0.15)
				)
				(justify right bottom mirror)
			)
		)
		(property "Value" "C_47u_0603"
			(at 0 -1.6 0)
			(layer "B.Fab")
			(effects
				(font
					(size 0.7 0.7)
					(thickness 0.15)
				)
				(justify right bottom mirror)
			)
		)
		(property "Datasheet" "https://www.murata.com/products/productdetail?partno=GRM188R60J476ME15%23"
			(at 0 0 0)
			(layer "F.Fab")
			(hide yes)
			(effects
				(font
					(size 1.27 1.27)
					(thickness 0.15)
				)
			)
		)
		(property "Author" "Antmicro"
			(at 0 0 0)
			(layer "B.Fab")
			(hide yes)
			(effects
				(font
					(size 1 1)
					(thickness 0.15)
				)
				(justify mirror)
			)
		)
		(property "Dielectric" ""
			(at 0 0 0)
			(layer "B.Fab")
			(hide yes)
			(effects
				(font
					(size 1 1)
					(thickness 0.15)
				)
				(justify mirror)
			)
		)
		(property "License" "Apache-2.0"
			(at 0 0 0)
			(layer "B.Fab")
			(hide yes)
			(effects
				(font
					(size 1 1)
					(thickness 0.15)
				)
				(justify mirror)
			)
		)
		(property "MPN" "GRM188R60J476ME15D"
			(at 0 0 0)
			(layer "B.Fab")
			(hide yes)
			(effects
				(font
					(size 1 1)
					(thickness 0.15)
				)
				(justify mirror)
			)
		)
		(property "Manufacturer" "Murata"
			(at 0 0 0)
			(layer "B.Fab")
			(hide yes)
			(effects
				(font
					(size 1 1)
					(thickness 0.15)
				)
				(justify mirror)
			)
		)
		(property "Val" "47u"
			(at 0 0 0)
			(layer "B.Fab")
			(hide yes)
			(effects
				(font
					(size 1 1)
					(thickness 0.15)
				)
				(justify mirror)
			)
		)
		(property "Voltage" ""
			(at 0 0 0)
			(layer "B.Fab")
			(hide yes)
			(effects
				(font
					(size 1 1)
					(thickness 0.15)
				)
				(justify mirror)
			)
		)
		(sheetname "/FPGA power/")
		(sheetfile "fpga-power.kicad_sch")
		(attr smd)
		(fp_line
			(start -0.3 -0.3)
			(end 0.3 -0.3)
			(stroke
				(width 0.15)
				(type solid)
			)
			(layer "B.SilkS")
		)
		(fp_line
			(start -0.3 0.3)
			(end 0.3 0.3)
			(stroke
				(width 0.15)
				(type solid)
			)
			(layer "B.SilkS")
		)
		(fp_rect
			(start -1.24 0.7)
			(end 1.24 -0.7)
			(stroke
				(width 0.05)
				(type solid)
			)
			(fill no)
			(layer "B.CrtYd")
		)
		(fp_rect
			(start -0.8 0.4)
			(end 0.8 -0.4)
			(stroke
				(width 0.15)
				(type solid)
			)
			(fill no)
			(layer "B.Fab")
		)
		(pad "1" smd roundrect
			(at -0.7 0)
			(size 0.6 0.8)
			(layers "B.Cu" "B.Mask" "B.Paste")
			(roundrect_rratio 0.2)
			(net 206 "+1V1")
			(pintype "passive")
		)
		(pad "2" smd roundrect
			(at 0.7 0)
			(size 0.6 0.8)
			(layers "B.Cu" "B.Mask" "B.Paste")
			(roundrect_rratio 0.2)
			(net 1 "GND")
			(pintype "passive")
		)
	)
)
